# BASEBOARD_FAB2 (Tioga Pass) — schematic parts with pin connectivity, parts 2284–2299 of 4751; source: Cadence DE-HDL packaged netlist (pstxprt.dat, pstxnet.dat, pstchip.dat)

EU4D5  PXE1110B  IC  pkg QFN  page 213
  1  DNC(0)  NC  = NC
  2  DNC(1)  NC  = NC
  3  BPWM1  OUT  = NC
  4  DNC(2)  NC  = NC
  5  APWM1  OUT  = VR_PVCCIO_CPU1_PWM1
  6  SDA  BI  = SMB_VR_STBY_LVC3_SDA
  7  SCL  BI  = SMB_VR_STBY_LVC3_SCL
  8  RESET_N  IN  = NC
  9  AVRRDY  OUT  = PWRGD_PVCCIO_CPU1_R
  10  AVREN  IN  = VR_PVCCIO_CPU1_EN
  11  VRHOT_N  OUT  = IRQ_PVCCIO_CPU1_VRHOT_N
  12  PINALRT_N  OUT  = NC
  13  MP0  BI  = NC
  14  MP1  BI  = NC
  15  VCLK  IN  = SVID_CLK_PVCCIO_CPU1
  16  VDIO  BI  = SVID_VDIO_PVCCIO_CPU1
  17  VALRT_N  OUT  = SVID_ALERT_PVCCIO_CPU1
  18  MP2  OUT  = NC
  19  AVSEN  IN  = VR_PVCCIO_CPU1_AVSP
  20  AVREF  IN  = VSENSE_PVCCIO_CPU1_AVSN
  21  AIREF1  IN  = VR_PVCCIO_CPU1_AIREF1
  22  AISEN1  IN  = ISENSE_PVCCIO_CPU1_PH1_IMON
  23  GND(1)  GROUND  = GND
  24  DNC(3)  NC  = NC
  25  BIREF1  IN  = NC
  26  BISEN1  IN  = GND
  27  GND(0)  GROUND  = GND
  28  DNC(4)  NC  = NC
  29  BVSEN  IN  = NC
  30  BVREF  IN  = NC
  31  MP3  BI  = NC
  32  MP4  BI  = PU_VR_PVCCIO_CPU1_FAULT1
  33  XADDR2  IN  = VR_PVCCIO_CPU1_XADDR2
  34  BTSEN  IN  = NC
  35  ATSEN  IN  = A_TSENSE_PVCCIO_CPU1
  36  XADDR1  IN  = VR_PVCCIO_CPU1_XADDR1
  37  VINSEN  IN  = VR_PVCCIO_CPU1_VINSEN
  38  IINSEN  IN  = NC
  39  VDD  POWER  = VR_PVCCIO_CPU1_VDD
  40  VD12  POWER  = VR_PVCCIO_CPU1_VD12
  41  THPAD  GROUND  = GND

EU4D6  IR354XX  IR35411 IC  pkg SM  page 202
  1  VOS  BI  = PVCCIN_CPU0
  2  LGND  GROUND  = GND
  3  VCC  POWER  = VR_PVCCIN_CPU0_PH2_VCIN
  4  VDRV  BI  = P5V_STBY
  5  PGND(0)  GROUND  = GND
  6  GL(0)  BI  = TP_PVCCIN_CPU0_PH2_GL_0
  7  PGND(1)  GROUND  = GND
  10  SW  BI  = VR_PVCCIN_CPU0_PHASE2
  25  VIN(0)  POWER  = VR_FET_SW_P12V_STBY_PVCCIN_CPU0
  30  VIN(1)  POWER  = VR_FET_SW_P12V_STBY_PVCCIN_CPU0
  31  NC  NC  = NC
  32  PHASE  BI  = VR_PVCCIN_CPU0_PH2_PHASE
  33  BOOST  BI  = VR_PVCCIN_CPU0_PH2_BOOT_R
  34  PWM  IN  = VR_PVCCIN_CPU0_PWM2
  35  EN  BI  = P5V_STBY
  36  TOUT_FLT  BI  = A_TSENSE_PVCCIN_CPU0
  37  OCSET  BI  = VR_PVCCIN_CPU0_PH2_OCSET
  38  IOUT  OUT  = ISENSE_PVCCIN_CPU0_PH2_IMON
  39  REFIN  IN  = VR_PVCCIN_CPU0_AIREF2
  40  PGND(2)  GROUND  = GND
  41  GL(1)  BI  = TP_PVCCIN_CPU0_PH2_GL_1

EU4E1  IR354XX  IR35411 IC  pkg SM  page 202
  1  VOS  BI  = PVCCIN_CPU0
  2  LGND  GROUND  = GND
  3  VCC  POWER  = VR_PVCCIN_CPU0_PH1_VCIN
  4  VDRV  BI  = P5V_STBY
  5  PGND(0)  GROUND  = GND
  6  GL(0)  BI  = TP_PVCCIN_CPU0_PH1_GL_0
  7  PGND(1)  GROUND  = GND
  10  SW  BI  = VR_PVCCIN_CPU0_PHASE1
  25  VIN(0)  POWER  = VR_FET_SW_P12V_STBY_PVCCIN_CPU0
  30  VIN(1)  POWER  = VR_FET_SW_P12V_STBY_PVCCIN_CPU0
  31  NC  NC  = NC
  32  PHASE  BI  = VR_PVCCIN_CPU0_PH1_PHASE
  33  BOOST  BI  = VR_PVCCIN_CPU0_PH1_BOOT_R
  34  PWM  IN  = VR_PVCCIN_CPU0_PWM1
  35  EN  BI  = P5V_STBY
  36  TOUT_FLT  BI  = A_TSENSE_PVCCIN_CPU0
  37  OCSET  BI  = VR_PVCCIN_CPU0_PH1_OCSET
  38  IOUT  OUT  = ISENSE_PVCCIN_CPU0_PH1_IMON
  39  REFIN  IN  = VR_PVCCIN_CPU0_AIREF1
  40  PGND(2)  GROUND  = GND
  41  GL(1)  BI  = TP_PVCCIN_CPU0_PH1_GL_1

EU4E2  IR354XX  IR35412 IC  pkg SM  page 214
  1  VOS  BI  = PVCCIO_CPU1
  2  LGND  GROUND  = GND
  3  VCC  POWER  = VR_PVCCIO_CPU1_PH1_VCIN
  4  VDRV  BI  = P5V_STBY
  5  PGND(0)  GROUND  = GND
  6  GL(0)  BI  = TP_PVCCIO_CPU1_GL_0
  7  PGND(1)  GROUND  = GND
  10  SW  BI  = VR_PVCCIO_CPU1_PH1_SW
  25  VIN(0)  POWER  = VR_FET_SW_P12V_STBY_PVCCIN_CPU0
  30  VIN(1)  POWER  = VR_FET_SW_P12V_STBY_PVCCIN_CPU0
  31  NC  NC  = NC
  32  PHASE  BI  = VR_PVCCIO_CPU1_PH1_PHASE
  33  BOOST  BI  = VR_PVCCIO_CPU1_PH1_BOOT_R
  34  PWM  IN  = VR_PVCCIO_CPU1_PWM1
  35  EN  BI  = P5V_STBY
  36  TOUT_FLT  BI  = A_TSENSE_PVCCIO_CPU1
  37  OCSET  BI  = VR_PVCCIO_CPU1_OCSET
  38  IOUT  OUT  = ISENSE_PVCCIO_CPU1_PH1_IMON
  39  REFIN  IN  = VR_PVCCIO_CPU1_AIREF1
  40  PGND(2)  GROUND  = GND
  41  GL(1)  BI  = TP_PVCCIO_CPU1_GL_1

EU4G1  NCP3232L  IC  pkg SM  page 233
  1  SS  BI  = VR_PVPP_GHJ_SS
  2  FB  BI  = VR_FB_PVPP_GHJ
  3  COMP  OUT  = VR_COMP_PVPP_GHJ_3
  4  ISET  BI  = VR_PVPP_GHJ_ISET
  5  AGND  GROUND  = AGND_PVPP_GHJ
  6  OTS  IN  = AGND_PVPP_GHJ
  7  PG  BI  = PWRGD_PVPP_GHJ_R
  8  VIN(0)  IN  = VR_FET_SW_P12V_STBY_PVPP_GHJ
  9  VIN(1)  IN  = VR_FET_SW_P12V_STBY_PVPP_GHJ
  10  VIN(2)  IN  = VR_FET_SW_P12V_STBY_PVPP_GHJ
  11  VIN(3)  IN  = VR_FET_SW_P12V_STBY_PVPP_GHJ
  12  VIN(4)  IN  = VR_FET_SW_P12V_STBY_PVPP_GHJ
  13  VIN(5)  IN  = VR_FET_SW_P12V_STBY_PVPP_GHJ
  14  VIN(6)  IN  = VR_FET_SW_P12V_STBY_PVPP_GHJ
  15  VSWH(0)  BI  = VR_PVPP_GHJ_PHASE
  16  PGND(0)  GROUND  = GND
  17  PGND(1)  GROUND  = GND
  18  PGND(2)  GROUND  = GND
  19  PGND(3)  GROUND  = GND
  20  PGND(4)  GROUND  = GND
  21  PGND(5)  GROUND  = GND
  22  PGND(6)  GROUND  = GND
  23  PGND(7)  GROUND  = GND
  24  PGND(8)  GROUND  = GND
  25  PGND(9)  GROUND  = GND
  26  PGND(10)  GROUND  = GND
  27  PGND(11)  GROUND  = GND
  28  PGND(12)  GROUND  = GND
  29  VSWH(1)  BI  = VR_PVPP_GHJ_PHASE
  30  VSWH(2)  BI  = VR_PVPP_GHJ_PHASE
  31  VSWH(3)  BI  = VR_PVPP_GHJ_PHASE
  32  VSWH(4)  BI  = VR_PVPP_GHJ_PHASE
  33  VSWH(5)  BI  = VR_PVPP_GHJ_PHASE
  34  VSWH(6)  BI  = VR_PVPP_GHJ_PHASE
  35  VSW  BI  = VR_PVPP_GHJ_PHASE
  36  BST  IN  = VR_PVPP_GHJ_BOOT
  37  PGND(13)  GROUND  = GND
  38  VB  OUT  = VR_VB_PVPP_GHJ
  39  VCC  POWER  = VR_FET_SW_P12V_STBY_PVPP_GHJ
  40  EN  IN  = FM_PVPP_PVDDQ_CPU1_EN_GHJ
  41  GND  GROUND  = GND
  42  VIN(7)  IN  = VR_FET_SW_P12V_STBY_PVPP_GHJ
  43  VSWH(7)  BI  = VR_PVPP_GHJ_PHASE

EU4G2  MIC5166  IC  pkg DFN  page 229
  1  VREF  OUT  = VR_PVTT_GHJ_VREF
  2  BIAS  BI  = VR_PVTT_GHJ_BIAS
  3  AGND  GROUND  = GND
  4  VDDQ  POWER  = VSENSE_PVDDQ_GHJ_VTT
  5  PG  OUT  = PWRGD_PVTT_GHJ_CPU1_R
  6  SNS  IN  = VR_PVTT_GHJ_SNS
  7  EN  IN  = FM_PVTT_GHJ_EN_R
  8  PGND  GROUND  = GND
  9  VTT  OUT  = PVTT_GHJ
  10  VIN  POWER  = PVDDQ_GHJ
  11  THPAD  GROUND  = GND

EU4G3  MIC5166  IC  pkg DFN  page 221
  1  VREF  OUT  = VR_PVTT_ABC_VREF
  2  BIAS  BI  = VR_PVTT_ABC_BIAS
  3  AGND  GROUND  = GND
  4  VDDQ  POWER  = VSENSE_PVDDQ_ABC_VTT
  5  PG  OUT  = PWRGD_PVTT_ABC_CPU0_R
  6  SNS  IN  = VR_PVTT_ABC_SNS
  7  EN  IN  = FM_PVTT_ABC_EN_R
  8  PGND  GROUND  = GND
  9  VTT  OUT  = PVTT_ABC
  10  VIN  POWER  = PVDDQ_ABC
  11  THPAD  GROUND  = GND

EU7A1  IR354XX  IR35411 IC  pkg SM  page 219
  1  VOS  BI  = PVDDQ_DEF
  2  LGND  GROUND  = GND
  3  VCC  POWER  = VR_PVDDQ_DEF_PH1_VCIN
  4  VDRV  BI  = P5V_STBY
  5  PGND(0)  GROUND  = GND
  6  GL(0)  BI  = TP_PVDDQ_DEF_PH1_GL_0
  7  PGND(1)  GROUND  = GND
  10  SW  BI  = VR_PVDDQ_DEF_PH1_SW
  25  VIN(0)  POWER  = VR_FET_SW_P12V_STBY_PVDDQ_DEF
  30  VIN(1)  POWER  = VR_FET_SW_P12V_STBY_PVDDQ_DEF
  31  NC  NC  = NC
  32  PHASE  BI  = VR_PVDDQ_DEF_PH1_PHASE
  33  BOOST  BI  = VR_PVDDQ_DEF_PH1_BOOT_R
  34  PWM  IN  = VR_PVDDQ_DEF_PWM1
  35  EN  BI  = P5V_STBY
  36  TOUT_FLT  BI  = A_TSENSE_PVDDQ_DEF
  37  OCSET  BI  = VR_PVDDQ_DEF_PH1_OCSET
  38  IOUT  OUT  = ISENSE_PVDDQ_DEF_PH1_IMON
  39  REFIN  IN  = VR_PVDDQ_DEF_AIREF1
  40  PGND(2)  GROUND  = GND
  41  GL(1)  BI  = TP_PVDDQ_DEF_PH1_GL_1

EU7A2  IR354XX  IR35412 IC  pkg SM  page 236
  1  VOS  BI  = P1V05_PCH_STBY
  2  LGND  GROUND  = GND
  3  VCC  POWER  = VR_P1V05_PCH_STBY_PH1_VCIN
  4  VDRV  BI  = P5V_STBY
  5  PGND(0)  GROUND  = GND
  6  GL(0)  BI  = TP_P1V05_PCH_GL_0
  7  PGND(1)  GROUND  = GND
  10  SW  BI  = VR_P1V05_PCH_STBY_PH1_PHASE_SW
  25  VIN(0)  POWER  = VR_FET_SW_P12V_STBY_PVDDQ_DEF
  30  VIN(1)  POWER  = VR_FET_SW_P12V_STBY_PVDDQ_DEF
  31  NC  NC  = NC
  32  PHASE  BI  = VR_P1V05_PCH_STBY_PH1_PHASE
  33  BOOST  BI  = VR_P1V05_PCH_STBY_PH1_BOOT_R
  34  PWM  IN  = VR_P1V05_PCH_STBY_PWM1
  35  EN  BI  = P5V_STBY
  36  TOUT_FLT  BI  = A_TSENSE_P1V05_PCH_STBY_TMON
  37  OCSET  BI  = VR_P1V05_PCH_STBY_OCSET
  38  IOUT  OUT  = ISENSE_P1V05_PCH_STBY_PH1_IMON
  39  REFIN  IN  = VR_P1V05_PCH_BIREF1
  40  PGND(2)  GROUND  = GND
  41  GL(1)  BI  = TP_P1V05_PCH_GL_1

EU7A3  IR354XX  IR35412 IC  pkg SM  page 236
  1  VOS  BI  = PVNN_PCH_STBY
  2  LGND  GROUND  = GND
  3  VCC  POWER  = VR_PVNN_PCH_PH1_VCIN
  4  VDRV  BI  = P5V_STBY
  5  PGND(0)  GROUND  = GND
  6  GL(0)  BI  = TP_PVNN_PCH_GL_0
  7  PGND(1)  GROUND  = GND
  10  SW  BI  = VR_PVNN_PCH_PH1_PHASE_SW
  25  VIN(0)  POWER  = VR_FET_SW_P12V_STBY_PVDDQ_DEF
  30  VIN(1)  POWER  = VR_FET_SW_P12V_STBY_PVDDQ_DEF
  31  NC  NC  = NC
  32  PHASE  BI  = VR_PVNN_PCH_PH1_PHASE
  33  BOOST  BI  = VR_PVNN_PCH_PH1_BOOT_R
  34  PWM  IN  = VR_PVNN_PCH_PWM1
  35  EN  BI  = P5V_STBY
  36  TOUT_FLT  BI  = A_TSENSE_PVNN_PCH_TMON
  37  OCSET  BI  = VR_PVNN_PCH_STBY_OCSET
  38  IOUT  OUT  = ISENSE_PVNN_PCH_PH1_IMON
  39  REFIN  IN  = VR_PVNN_PCH_AIREF1
  40  PGND(2)  GROUND  = GND
  41  GL(1)  BI  = TP_PVNN_PCH_GL_1

EU7A4  IR354XX  IR35411 IC  pkg SM  page 219
  1  VOS  BI  = PVDDQ_DEF
  2  LGND  GROUND  = GND
  3  VCC  POWER  = VR_PVDDQ_DEF_PH2_VCIN
  4  VDRV  BI  = P5V_STBY
  5  PGND(0)  GROUND  = GND
  6  GL(0)  BI  = TP_PVDDQ_DEF_PH2_GL_0
  7  PGND(1)  GROUND  = GND
  10  SW  BI  = VR_PVDDQ_DEF_PH2_SW
  25  VIN(0)  POWER  = VR_FET_SW_P12V_STBY_PVDDQ_DEF
  30  VIN(1)  POWER  = VR_FET_SW_P12V_STBY_PVDDQ_DEF
  31  NC  NC  = NC
  32  PHASE  BI  = VR_PVDDQ_DEF_PH2_PHASE
  33  BOOST  BI  = VR_PVDDQ_DEF_PH2_BOOT_R
  34  PWM  IN  = VR_PVDDQ_DEF_PWM2
  35  EN  BI  = P5V_STBY
  36  TOUT_FLT  BI  = A_TSENSE_PVDDQ_DEF
  37  OCSET  BI  = VR_PVDDQ_DEF_PH2_OCSET
  38  IOUT  OUT  = ISENSE_PVDDQ_DEF_PH2_IMON
  39  REFIN  IN  = VR_PVDDQ_DEF_AIREF2
  40  PGND(2)  GROUND  = GND
  41  GL(1)  BI  = TP_PVDDQ_DEF_PH2_GL_1

EU7A5  PXM1310B  IC  pkg QFN  page 218
  1  BPWM1  OUT  = NC
  2  DNC(0)  NC  = NC
  3  APWM3  OUT  = NC
  4  APWM2  OUT  = VR_PVDDQ_DEF_PWM2
  5  APWM1  OUT  = VR_PVDDQ_DEF_PWM1
  6  SDA  BI  = SMB_VR_STBY_LVC3_SDA
  7  SCL  BI  = SMB_VR_STBY_LVC3_SCL
  8  RESET_N  IN  = NC
  9  AVRRDY  OUT  = PWRGD_PVDDQ_DEF_R
  10  AVREN  IN  = VR_PVDDQ_DEF_VREN
  11  VRHOT_N  OUT  = IRQ_PVDDQ_DEF_VRHOT_LVT3_R_N
  12  PINALRT_N  OUT  = NC
  13  MP0  BI  = PU_VR_PVDDQ_DEF_FAULT1
  14  MP1  BI  = TP_PVDDQ_DEF_MP1
  15  VCLK  IN  = SVID_CLK_PVDDQ_DEF
  16  VDIO  BI  = SVID_VDIO_PVDDQ_DEF
  17  VALRT_N  OUT  = SVID_ALERT_PVDDQ_DEF
  18  MP2  BI  = TP_PVDDQ_DEF_MP2
  19  AVSEN  IN  = VR_PVDDQ_DEF_AVSP
  20  AVREF  IN  = VSENSE_PVDDQ_DEF_N
  21  AIREF1  IN  = VR_PVDDQ_DEF_AIREF1
  22  AISEN1  IN  = ISENSE_PVDDQ_DEF_PH1_IMON
  23  AIREF2  IN  = VR_PVDDQ_DEF_AIREF2
  24  AISEN2  IN  = ISENSE_PVDDQ_DEF_PH2_IMON
  25  AIREF3  IN  = NC
  26  AISEN3  IN  = NC
  27  GND  GROUND  = GND
  28  DNC(1)  NC  = NC
  29  BVSEN  IN  = NC
  30  BVREF  IN  = NC
  31  BIREF1  IN  = NC
  32  BISEN1  IN  = GND
  33  XADDR2  IN  = VR_PVDDQ_DEF_XADDR2
  34  BTSEN  IN  = NC
  35  ATSEN  IN  = A_TSENSE_PVDDQ_DEF
  36  XADDR1  IN  = VR_PVDDQ_DEF_XADDR1
  37  VINSEN  IN  = VR_PVDDQ_DEF_VINSEN
  38  IINSEN  IN  = VR_PVDDQ_DEF_AIINSEN
  39  VDD  POWER  = VR_PVDDQ_DEF_VDD
  40  VD12  BI  = VR_PVDDQ_DEF_VD12
  41  THPAD  GROUND  = GND

EU7B1  NCP3232L  IC  pkg SM  page 232
  1  SS  BI  = VR_PVPP_DEF_SS
  2  FB  BI  = VR_FB_PVPP_DEF
  3  COMP  OUT  = VR_COMP_PVPP_DEF_3
  4  ISET  BI  = VR_PVPP_DEF_ISET
  5  AGND  GROUND  = AGND_PVPP_DEF
  6  OTS  IN  = AGND_PVPP_DEF
  7  PG  BI  = PWRGD_PVPP_DEF_R
  8  VIN(0)  IN  = VR_FET_SW_P12V_STBY_PVPP_DEF
  9  VIN(1)  IN  = VR_FET_SW_P12V_STBY_PVPP_DEF
  10  VIN(2)  IN  = VR_FET_SW_P12V_STBY_PVPP_DEF
  11  VIN(3)  IN  = VR_FET_SW_P12V_STBY_PVPP_DEF
  12  VIN(4)  IN  = VR_FET_SW_P12V_STBY_PVPP_DEF
  13  VIN(5)  IN  = VR_FET_SW_P12V_STBY_PVPP_DEF
  14  VIN(6)  IN  = VR_FET_SW_P12V_STBY_PVPP_DEF
  15  VSWH(0)  BI  = VR_PVPP_DEF_PHASE
  16  PGND(0)  GROUND  = GND
  17  PGND(1)  GROUND  = GND
  18  PGND(2)  GROUND  = GND
  19  PGND(3)  GROUND  = GND
  20  PGND(4)  GROUND  = GND
  21  PGND(5)  GROUND  = GND
  22  PGND(6)  GROUND  = GND
  23  PGND(7)  GROUND  = GND
  24  PGND(8)  GROUND  = GND
  25  PGND(9)  GROUND  = GND
  26  PGND(10)  GROUND  = GND
  27  PGND(11)  GROUND  = GND
  28  PGND(12)  GROUND  = GND
  29  VSWH(1)  BI  = VR_PVPP_DEF_PHASE
  30  VSWH(2)  BI  = VR_PVPP_DEF_PHASE
  31  VSWH(3)  BI  = VR_PVPP_DEF_PHASE
  32  VSWH(4)  BI  = VR_PVPP_DEF_PHASE
  33  VSWH(5)  BI  = VR_PVPP_DEF_PHASE
  34  VSWH(6)  BI  = VR_PVPP_DEF_PHASE
  35  VSW  BI  = VR_PVPP_DEF_PHASE
  36  BST  IN  = VR_PVPP_DEF_BOOT
  37  PGND(13)  GROUND  = GND
  38  VB  OUT  = VR_VB_PVPP_DEF
  39  VCC  POWER  = VR_FET_SW_P12V_STBY_PVPP_DEF
  40  EN  IN  = FM_PVPP_PVDDQ_CPU0_EN_DEF
  41  GND  GROUND  = GND
  42  VIN(7)  IN  = VR_FET_SW_P12V_STBY_PVPP_DEF
  43  VSWH(7)  BI  = VR_PVPP_DEF_PHASE

EU7C1  IR354XX  IR35412 IC  pkg SM  page 212
  1  VOS  BI  = PVCCIO_CPU0
  2  LGND  GROUND  = GND
  3  VCC  POWER  = VR_PVCCIO_CPU0_PH1_VCIN
  4  VDRV  BI  = P5V_STBY
  5  PGND(0)  GROUND  = GND
  6  GL(0)  BI  = TP_PVCCIO_CPU0_GL_0
  7  PGND(1)  GROUND  = GND
  10  SW  BI  = VR_PVCCIO_CPU0_PH1_SW
  25  VIN(0)  POWER  = VR_FET_SW_P12V_STBY_PVCCIO_CPU0
  30  VIN(1)  POWER  = VR_FET_SW_P12V_STBY_PVCCIO_CPU0
  31  NC  NC  = NC
  32  PHASE  BI  = VR_PVCCIO_CPU0_PH1_PHASE
  33  BOOST  BI  = VR_PVCCIO_CPU0_PH1_BOOT_R
  34  PWM  IN  = VR_PVCCIO_CPU0_PWM1
  35  EN  BI  = P5V_STBY
  36  TOUT_FLT  BI  = A_TSENSE_PVCCIO_CPU0
  37  OCSET  BI  = VR_PVCCIO_CPU0_OCSET
  38  IOUT  OUT  = ISENSE_PVCCIO_CPU0_PH1_IMON
  39  REFIN  IN  = VR_PVCCIO_CPU0_AIREF1
  40  PGND(2)  GROUND  = GND
  41  GL(1)  BI  = TP_PVCCIO_CPU0_GL_1

EU7E1  SLG55021  IC  pkg SM  page 198
  1  VCC  POWER  = P5V_STBY
  2  \on\  IN  = FM_P12V_MAIN_SW_EN
  3  SHDN_N  IN  = P5V_STBY
  4  GND  GROUND  = GND
  5  D  IN  = P12V_STBY
  6  S  IN  = P12V
  7  G  OUT  = P12V_SWITCH_G
  8  PG  OUT  = TP_SLG55021_P12V_MAIN_8
  9  THPAD  GROUND  = GND

EU7E2  TPS54821  IC  pkg LCC  page 241
  1  RT_CLK  IN  = VR_P5V_STBY_RT
  2  GND(0)  GROUND  = GND
  3  GND(1)  GROUND  = GND
  4  PVIN(0)  IN  = VR_FET_SW_P5V_STBY_PVIN
  5  PVIN(1)  IN  = VR_FET_SW_P5V_STBY_PVIN
  6  VIN  IN  = VR_P5V_STBY_VIN
  7  VSENSE  IN  = VR_P5V_STBY_VSENSE
  8  COMP  BI  = VR_P5V_STBY_COMP
  9  SS_TR  IN  = VR_P5V_STBY_SS
  10  EN  IN  = VR_P5V_STBY_EN
  11  PH(0)  OUT  = VR_P5V_STBY_PHASE
  12  PH(1)  OUT  = VR_P5V_STBY_PHASE
  13  BOOT  UNSPEC  = VR_P5V_STBY_BOOT
  14  PWRGD  OUT  = PWRGD_P5V_STBY_R
  15  THPAD  GROUND  = GND
